# T6G (Grand Teton) — schematic netlist excerpt (pin names and nets, part order shuffled) for the footprints in the layout excerpt that follows; sources: Cadence DE-HDL packaged netlist, KiCad conversion of 04192023_DAF0TMB3IC0_F0TG_MB_C_brd_V02_OCP.brd

R3438  Q_RES  100K 1% CHIP  pkg 0402LF  page 126 : A = P3V3_AUX ; B = GPU_BASE_HMC_READY_ISO
PR6563  Q_RES  1.5 1% EMPTY  pkg 0402LF  page 363 : A = SW_P0V9_RETIMER_CPU0_SW2_RC ; B = GND

(kicad_pcb
	(version 20260206)
	(generator "pcbnew")
	(generator_version "10.0")
	(general
		(thickness 1.6)
		(legacy_teardrops no)
	)
	(paper "A4")
	(title_block
		(title "04192023_DAF0TMB3IC0_F0TG_MB_C_brd_V02_OCP.brd")
		(comment 1 "Grand Teton / footprints 4161-4162 of 8354")
	)
	(layers
		(0 "F.Cu" signal "TOP")
		(4 "In1.Cu" signal "GND")
		(6 "In2.Cu" signal "IN1")
		(8 "In3.Cu" signal "GND1")
		(10 "In4.Cu" signal "IN2")
		(12 "In5.Cu" signal "GND2")
		(14 "In6.Cu" signal "IN3")
		(16 "In7.Cu" signal "GND3")
		(18 "In8.Cu" signal "VCC")
		(20 "In9.Cu" signal "VCC1")
		(22 "In10.Cu" signal "GND4")
		(24 "In11.Cu" signal "IN4")
		(26 "In12.Cu" signal "GND5")
		(28 "In13.Cu" signal "IN5")
		(30 "In14.Cu" signal "GND6")
		(32 "In15.Cu" signal "IN6")
		(34 "In16.Cu" signal "GND7")
		(2 "B.Cu" signal "BOTTOM")
		(9 "F.Adhes" user "F.Adhesive")
		(11 "B.Adhes" user "B.Adhesive")
		(13 "F.Paste" user "Package Geometry/Pastemask Top")
		(15 "B.Paste" user "Package Geometry/Pastemask Bottom")
		(5 "F.SilkS" user "Ref Des/Silkscreen Top")
		(7 "B.SilkS" user "Ref Des/Silkscreen Bottom")
		(1 "F.Mask" user "Board Geometry/Soldermask Top")
		(3 "B.Mask" user "Board Geometry/Soldermask Bottom")
		(17 "Dwgs.User" user "User.Drawings")
		(19 "Cmts.User" user "User.Comments")
		(21 "Eco1.User" user "User.Eco1")
		(23 "Eco2.User" user "User.Eco2")
		(25 "Edge.Cuts" user "Board Geometry/Outline")
		(27 "Margin" user)
		(31 "F.CrtYd" user "Package Geometry/Place Bound Top")
		(29 "B.CrtYd" user "Package Geometry/Place Bound Bottom")
		(35 "F.Fab" user "Ref Des/Assembly Top")
		(33 "B.Fab" user "Ref Des/Assembly Bottom")
	)
	(footprint ""
		(layer "F.Cu")
		(at 450.008752 -395.699234 90)
		(property "Reference" "PR6563"
			(at 0 0 90)
			(layer "F.SilkS")
			(hide yes)
			(effects
				(font
					(size 1.27 1.27)
				)
			)
		)
		(property "Value" ""
			(at 0 0 90)
			(layer "F.Fab")
			(effects
				(font
					(size 1.27 1.27)
				)
			)
		)
		(duplicate_pad_numbers_are_jumpers no)
		(fp_line
			(start 0.7874 -0.4064)
			(end 0.7874 0.4064)
			(stroke
				(width 0.1524)
				(type default)
			)
			(layer "F.SilkS")
		)
		(fp_line
			(start -0.7874 -0.4064)
			(end 0.7874 -0.4064)
			(stroke
				(width 0.1524)
				(type default)
			)
			(layer "F.SilkS")
		)
		(fp_line
			(start 0.7874 0.4064)
			(end -0.7874 0.4064)
			(stroke
				(width 0.1524)
				(type default)
			)
			(layer "F.SilkS")
		)
		(fp_line
			(start -0.7874 0.4064)
			(end -0.7874 -0.4064)
			(stroke
				(width 0.1524)
				(type default)
			)
			(layer "F.SilkS")
		)
		(fp_line
			(start -0.12065 -0.305054)
			(end -0.12065 -0.2794)
			(stroke
				(width 0.1)
				(type default)
			)
			(layer "F.Fab")
		)
		(fp_line
			(start -0.67945 -0.305054)
			(end -0.12065 -0.305054)
			(stroke
				(width 0.1)
				(type default)
			)
			(layer "F.Fab")
		)
		(fp_line
			(start 0.67945 -0.3048)
			(end 0.67945 0.3048)
			(stroke
				(width 0.1)
				(type default)
			)
			(layer "F.Fab")
		)
		(fp_line
			(start 0.12065 -0.3048)
			(end 0.67945 -0.3048)
			(stroke
				(width 0.1)
				(type default)
			)
			(layer "F.Fab")
		)
		(fp_line
			(start 0.12065 -0.2794)
			(end 0.12065 -0.3048)
			(stroke
				(width 0.1)
				(type default)
			)
			(layer "F.Fab")
		)
		(fp_line
			(start -0.12065 -0.2794)
			(end 0.12065 -0.2794)
			(stroke
				(width 0.1)
				(type default)
			)
			(layer "F.Fab")
		)
		(fp_line
			(start 0.120396 0.2794)
			(end -0.12065 0.2794)
			(stroke
				(width 0.1)
				(type default)
			)
			(layer "F.Fab")
		)
		(fp_line
			(start -0.12065 0.2794)
			(end -0.12065 0.3048)
			(stroke
				(width 0.1)
				(type default)
			)
			(layer "F.Fab")
		)
		(fp_line
			(start 0.67945 0.3048)
			(end 0.120396 0.3048)
			(stroke
				(width 0.1)
				(type default)
			)
			(layer "F.Fab")
		)
		(fp_line
			(start 0.120396 0.3048)
			(end 0.120396 0.2794)
			(stroke
				(width 0.1)
				(type default)
			)
			(layer "F.Fab")
		)
		(fp_line
			(start -0.12065 0.3048)
			(end -0.67945 0.3048)
			(stroke
				(width 0.1)
				(type default)
			)
			(layer "F.Fab")
		)
		(fp_line
			(start -0.67945 0.3048)
			(end -0.67945 -0.305054)
			(stroke
				(width 0.1)
				(type default)
			)
			(layer "F.Fab")
		)
		(pad "1" smd circle
			(at -0.40005 0 90)
			(size 0 0)
			(layers "F.Cu" "F.Mask" "F.Paste")
			(net "SW_P0V9_RETIMER_CPU0_SW2_RC")
		)
		(pad "2" smd circle
			(at 0.40005 0 90)
			(size 0 0)
			(layers "F.Cu" "F.Mask" "F.Paste")
			(net "GND")
		)
	)
	(footprint ""
		(layer "F.Cu")
		(at 163.4236 -436.153052)
		(property "Reference" "R3438"
			(at 0 0 0)
			(layer "F.SilkS")
			(hide yes)
			(effects
				(font
					(size 1.27 1.27)
				)
			)
		)
		(property "Value" ""
			(at 0 0 0)
			(layer "F.Fab")
			(effects
				(font
					(size 1.27 1.27)
				)
			)
		)
		(duplicate_pad_numbers_are_jumpers no)
		(fp_line
			(start -0.7874 -0.4064)
			(end 0.7874 -0.4064)
			(stroke
				(width 0.1524)
				(type default)
			)
			(layer "F.SilkS")
		)
		(fp_line
			(start -0.7874 0.4064)
			(end -0.7874 -0.4064)
			(stroke
				(width 0.1524)
				(type default)
			)
			(layer "F.SilkS")
		)
		(fp_line
			(start 0.7874 -0.4064)
			(end 0.7874 0.4064)
			(stroke
				(width 0.1524)
				(type default)
			)
			(layer "F.SilkS")
		)
		(fp_line
			(start 0.7874 0.4064)
			(end -0.7874 0.4064)
			(stroke
				(width 0.1524)
				(type default)
			)
			(layer "F.SilkS")
		)
		(fp_line
			(start -0.67945 -0.305054)
			(end -0.12065 -0.305054)
			(stroke
				(width 0.1)
				(type default)
			)
			(layer "F.Fab")
		)
		(fp_line
			(start -0.67945 0.3048)
			(end -0.67945 -0.305054)
			(stroke
				(width 0.1)
				(type default)
			)
			(layer "F.Fab")
		)
		(fp_line
			(start -0.12065 -0.305054)
			(end -0.12065 -0.2794)
			(stroke
				(width 0.1)
				(type default)
			)
			(layer "F.Fab")
		)
		(fp_line
			(start -0.12065 -0.2794)
			(end 0.12065 -0.2794)
			(stroke
				(width 0.1)
				(type default)
			)
			(layer "F.Fab")
		)
		(fp_line
			(start -0.12065 0.2794)
			(end -0.12065 0.3048)
			(stroke
				(width 0.1)
				(type default)
			)
			(layer "F.Fab")
		)
		(fp_line
			(start -0.12065 0.3048)
			(end -0.67945 0.3048)
			(stroke
				(width 0.1)
				(type default)
			)
			(layer "F.Fab")
		)
		(fp_line
			(start 0.120396 0.2794)
			(end -0.12065 0.2794)
			(stroke
				(width 0.1)
				(type default)
			)
			(layer "F.Fab")
		)
		(fp_line
			(start 0.120396 0.3048)
			(end 0.120396 0.2794)
			(stroke
				(width 0.1)
				(type default)
			)
			(layer "F.Fab")
		)
		(fp_line
			(start 0.12065 -0.3048)
			(end 0.67945 -0.3048)
			(stroke
				(width 0.1)
				(type default)
			)
			(layer "F.Fab")
		)
		(fp_line
			(start 0.12065 -0.2794)
			(end 0.12065 -0.3048)
			(stroke
				(width 0.1)
				(type default)
			)
			(layer "F.Fab")
		)
		(fp_line
			(start 0.67945 -0.3048)
			(end 0.67945 0.3048)
			(stroke
				(width 0.1)
				(type default)
			)
			(layer "F.Fab")
		)
		(fp_line
			(start 0.67945 0.3048)
			(end 0.120396 0.3048)
			(stroke
				(width 0.1)
				(type default)
			)
			(layer "F.Fab")
		)
		(pad "1" smd circle
			(at -0.40005 0)
			(size 0 0)
			(layers "F.Cu" "F.Mask" "F.Paste")
			(net "P3V3_AUX")
		)
		(pad "2" smd circle
			(at 0.40005 0)
			(size 0 0)
			(layers "F.Cu" "F.Mask" "F.Paste")
			(net "GPU_BASE_HMC_READY_ISO")
		)
	)
)
